(kicad_pcb
	(version 20260206)
	(generator "pcbnew")
	(generator_version "10.0")
	(general
		(thickness 1.6)
		(legacy_teardrops no)
	)
	(paper "A4")
	(title_block
		(title "v1-chassis-manager — T6M_CM_d_v01_1031_1645.brd")
		(comment 1 "Open CloudServer (Microsoft) / footprints 1835-1844 of 2512")
	)
	(layers
		(0 "F.Cu" signal "TOP")
		(4 "In1.Cu" signal "GND1")
		(6 "In2.Cu" signal "IN1")
		(8 "In3.Cu" signal "VCC1")
		(10 "In4.Cu" signal "VCC2")
		(12 "In5.Cu" signal "GND2")
		(14 "In6.Cu" signal "IN2")
		(16 "In7.Cu" signal "IN3")
		(18 "In8.Cu" signal "GND3")
		(2 "B.Cu" signal "BOTTOM")
		(9 "F.Adhes" user "F.Adhesive")
		(11 "B.Adhes" user "B.Adhesive")
		(13 "F.Paste" user "Package Geometry/Pastemask Top")
		(15 "B.Paste" user "Package Geometry/Pastemask Bottom")
		(5 "F.SilkS" user "Ref Des/Silkscreen Top")
		(7 "B.SilkS" user "Ref Des/Silkscreen Bottom")
		(1 "F.Mask" user "Board Geometry/Soldermask Top")
		(3 "B.Mask" user "Board Geometry/Soldermask Bottom")
		(17 "Dwgs.User" user "User.Drawings")
		(19 "Cmts.User" user "User.Comments")
		(21 "Eco1.User" user "User.Eco1")
		(23 "Eco2.User" user "User.Eco2")
		(25 "Edge.Cuts" user "Board Geometry/Outline")
		(27 "Margin" user)
		(31 "F.CrtYd" user "Package Geometry/Place Bound Top")
		(29 "B.CrtYd" user "Package Geometry/Place Bound Bottom")
		(35 "F.Fab" user "Ref Des/Assembly Top")
		(33 "B.Fab" user "Ref Des/Assembly Bottom")
	)
	(footprint ""
		(layer "B.Cu")
		(at 167.658288 -152.901904)
		(property "Reference" "C450"
			(at 4.65582 0.340614 0)
			(unlocked yes)
			(layer "B.SilkS")
			(effects
				(font
					(size 0.7874 0.5842)
					(thickness 0.1524)
				)
				(justify left mirror)
			)
		)
		(property "Value" ""
			(at 0 0 0)
			(layer "B.Fab")
			(effects
				(font
					(size 1.27 1.27)
				)
				(justify mirror)
			)
		)
		(duplicate_pad_numbers_are_jumpers no)
		(fp_line
			(start -0.7874 -0.4064)
			(end -0.7874 0.4064)
			(stroke
				(width 0.1524)
				(type default)
			)
			(layer "B.SilkS")
		)
		(fp_line
			(start -0.7874 0.4064)
			(end 0.7874 0.4064)
			(stroke
				(width 0.1524)
				(type default)
			)
			(layer "B.SilkS")
		)
		(fp_line
			(start 0 0.381)
			(end 0 -0.381)
			(stroke
				(width 0.1524)
				(type default)
			)
			(layer "B.SilkS")
		)
		(fp_line
			(start 0.7874 -0.4064)
			(end -0.7874 -0.4064)
			(stroke
				(width 0.1524)
				(type default)
			)
			(layer "B.SilkS")
		)
		(fp_line
			(start 0.7874 0.4064)
			(end 0.7874 -0.4064)
			(stroke
				(width 0.1524)
				(type default)
			)
			(layer "B.SilkS")
		)
		(fp_poly
			(pts
				(xy 0.5334 0.254) (xy 0.635 0.254) (xy 0.635 0.2286) (xy 0.635 -0.254) (xy 0.5334 -0.254) (xy 0.5334 -0.2794)
				(xy -0.5334 -0.2794) (xy -0.5334 -0.254) (xy -0.635 -0.254) (xy -0.635 0.254) (xy -0.5334 0.254)
				(xy -0.5334 0.2794) (xy 0.508 0.2794) (xy 0.5334 0.2794)
			)
			(stroke
				(width 0)
				(type default)
			)
			(fill no)
			(layer "B.CrtYd")
		)
		(pad "1" smd rect
			(at -0.40005 0 180)
			(size 0.4572 0.508)
			(layers "B.Cu" "B.Mask" "B.Paste")
			(net "P1V9_LAN2")
		)
		(pad "2" smd rect
			(at 0.40005 0 180)
			(size 0.4572 0.508)
			(layers "B.Cu" "B.Mask" "B.Paste")
			(net "GND")
		)
	)
	(footprint ""
		(layer "B.Cu")
		(at 110.44936 -178.601624 180)
		(property "Reference" "R714"
			(at 21.356828 -32.269176 0)
			(unlocked yes)
			(layer "B.SilkS")
			(effects
				(font
					(size 0.7874 0.5842)
					(thickness 0.1524)
				)
				(justify left mirror)
			)
		)
		(property "Value" ""
			(at 0 0 0)
			(layer "B.Fab")
			(effects
				(font
					(size 1.27 1.27)
				)
				(justify mirror)
			)
		)
		(duplicate_pad_numbers_are_jumpers no)
		(fp_line
			(start 0.7874 0.4064)
			(end 0.7874 -0.4064)
			(stroke
				(width 0.1524)
				(type default)
			)
			(layer "B.SilkS")
		)
		(fp_line
			(start 0.7874 -0.4064)
			(end -0.7874 -0.4064)
			(stroke
				(width 0.1524)
				(type default)
			)
			(layer "B.SilkS")
		)
		(fp_line
			(start -0.7874 0.4064)
			(end 0.7874 0.4064)
			(stroke
				(width 0.1524)
				(type default)
			)
			(layer "B.SilkS")
		)
		(fp_line
			(start -0.7874 -0.4064)
			(end -0.7874 0.4064)
			(stroke
				(width 0.1524)
				(type default)
			)
			(layer "B.SilkS")
		)
		(fp_poly
			(pts
				(xy 0.508 0.2794) (xy 0.508 0.2286) (xy 0.635 0.2286) (xy 0.635 -0.254) (xy 0.5334 -0.254) (xy 0.5334 -0.2794)
				(xy -0.5334 -0.2794) (xy -0.5334 -0.254) (xy -0.635 -0.254) (xy -0.635 0.254) (xy -0.5334 0.254)
				(xy -0.5334 0.2794)
			)
			(stroke
				(width 0)
				(type default)
			)
			(fill no)
			(layer "B.CrtYd")
		)
		(pad "1" smd rect
			(at -0.40005 0)
			(size 0.4572 0.508)
			(layers "B.Cu" "B.Mask" "B.Paste")
			(net "T6_NODE1_EN")
		)
		(pad "2" smd rect
			(at 0.40005 0)
			(size 0.4572 0.508)
			(layers "B.Cu" "B.Mask" "B.Paste")
			(net "P5V_NODE1")
		)
	)
	(footprint ""
		(layer "B.Cu")
		(at 137.65276 -187.872624 -90)
		(property "Reference" "C630"
			(at -4.565396 1.448308 270)
			(unlocked yes)
			(layer "B.SilkS")
			(effects
				(font
					(size 0.7874 0.5842)
					(thickness 0.1524)
				)
				(justify left mirror)
			)
		)
		(property "Value" ""
			(at 0 0 90)
			(layer "B.Fab")
			(effects
				(font
					(size 1.27 1.27)
				)
				(justify mirror)
			)
		)
		(duplicate_pad_numbers_are_jumpers no)
		(fp_line
			(start -0.7874 0.4064)
			(end 0.7874 0.4064)
			(stroke
				(width 0.1524)
				(type default)
			)
			(layer "B.SilkS")
		)
		(fp_line
			(start 0.7874 0.4064)
			(end 0.7874 -0.4064)
			(stroke
				(width 0.1524)
				(type default)
			)
			(layer "B.SilkS")
		)
		(fp_line
			(start 0 0.381)
			(end 0 -0.381)
			(stroke
				(width 0.1524)
				(type default)
			)
			(layer "B.SilkS")
		)
		(fp_line
			(start -0.7874 -0.4064)
			(end -0.7874 0.4064)
			(stroke
				(width 0.1524)
				(type default)
			)
			(layer "B.SilkS")
		)
		(fp_line
			(start 0.7874 -0.4064)
			(end -0.7874 -0.4064)
			(stroke
				(width 0.1524)
				(type default)
			)
			(layer "B.SilkS")
		)
		(fp_poly
			(pts
				(xy 0.5334 0.254) (xy 0.635 0.254) (xy 0.635 0.2286) (xy 0.635 -0.254) (xy 0.5334 -0.254) (xy 0.5334 -0.2794)
				(xy -0.5334 -0.2794) (xy -0.5334 -0.254) (xy -0.635 -0.254) (xy -0.635 0.254) (xy -0.5334 0.254)
				(xy -0.5334 0.2794) (xy 0.508 0.2794) (xy 0.5334 0.2794)
			)
			(stroke
				(width 0)
				(type default)
			)
			(fill no)
			(layer "B.CrtYd")
		)
		(pad "1" smd rect
			(at -0.40005 0 90)
			(size 0.4572 0.508)
			(layers "B.Cu" "B.Mask" "B.Paste")
			(net "T9_NODE3_EN_R")
		)
		(pad "2" smd rect
			(at 0.40005 0 90)
			(size 0.4572 0.508)
			(layers "B.Cu" "B.Mask" "B.Paste")
			(net "GND")
		)
	)
	(footprint ""
		(layer "B.Cu")
		(at 121.412 -52.959 90)
		(property "Reference" "R1288"
			(at 1.778 -0.15367 270)
			(unlocked yes)
			(layer "B.SilkS")
			(effects
				(font
					(size 0.7874 0.5842)
					(thickness 0.1524)
				)
				(justify left mirror)
			)
		)
		(property "Value" ""
			(at 0 0 90)
			(layer "B.Fab")
			(effects
				(font
					(size 1.27 1.27)
				)
				(justify mirror)
			)
		)
		(duplicate_pad_numbers_are_jumpers no)
		(fp_line
			(start 0.7874 -0.4064)
			(end -0.7874 -0.4064)
			(stroke
				(width 0.1524)
				(type default)
			)
			(layer "B.SilkS")
		)
		(fp_line
			(start -0.7874 -0.4064)
			(end -0.7874 0.4064)
			(stroke
				(width 0.1524)
				(type default)
			)
			(layer "B.SilkS")
		)
		(fp_line
			(start 0.7874 0.4064)
			(end 0.7874 -0.4064)
			(stroke
				(width 0.1524)
				(type default)
			)
			(layer "B.SilkS")
		)
		(fp_line
			(start -0.7874 0.4064)
			(end 0.7874 0.4064)
			(stroke
				(width 0.1524)
				(type default)
			)
			(layer "B.SilkS")
		)
		(fp_poly
			(pts
				(xy 0.508 0.2794) (xy 0.508 0.2286) (xy 0.635 0.2286) (xy 0.635 -0.254) (xy 0.5334 -0.254) (xy 0.5334 -0.2794)
				(xy -0.5334 -0.2794) (xy -0.5334 -0.254) (xy -0.635 -0.254) (xy -0.635 0.254) (xy -0.5334 0.254)
				(xy -0.5334 0.2794)
			)
			(stroke
				(width 0)
				(type default)
			)
			(fill no)
			(layer "B.CrtYd")
		)
		(pad "1" smd rect
			(at -0.40005 0 270)
			(size 0.4572 0.508)
			(layers "B.Cu" "B.Mask" "B.Paste")
			(net "SIO_JTAG_CPLD1_TMS_R")
		)
		(pad "2" smd rect
			(at 0.40005 0 270)
			(size 0.4572 0.508)
			(layers "B.Cu" "B.Mask" "B.Paste")
			(net "P3V3_NODE1")
		)
	)
	(footprint ""
		(layer "B.Cu")
		(at 52.437538 -72.292718)
		(property "Reference" "C126"
			(at -13.565378 31.431738 0)
			(unlocked yes)
			(layer "B.SilkS")
			(effects
				(font
					(size 0.7874 0.5842)
					(thickness 0.1524)
				)
				(justify left mirror)
			)
		)
		(property "Value" ""
			(at 0 0 0)
			(layer "B.Fab")
			(effects
				(font
					(size 1.27 1.27)
				)
				(justify mirror)
			)
		)
		(duplicate_pad_numbers_are_jumpers no)
		(fp_line
			(start -0.7874 -0.4064)
			(end -0.7874 0.4064)
			(stroke
				(width 0.1524)
				(type default)
			)
			(layer "B.SilkS")
		)
		(fp_line
			(start -0.7874 0.4064)
			(end 0.7874 0.4064)
			(stroke
				(width 0.1524)
				(type default)
			)
			(layer "B.SilkS")
		)
		(fp_line
			(start 0 0.381)
			(end 0 -0.381)
			(stroke
				(width 0.1524)
				(type default)
			)
			(layer "B.SilkS")
		)
		(fp_line
			(start 0.7874 -0.4064)
			(end -0.7874 -0.4064)
			(stroke
				(width 0.1524)
				(type default)
			)
			(layer "B.SilkS")
		)
		(fp_line
			(start 0.7874 0.4064)
			(end 0.7874 -0.4064)
			(stroke
				(width 0.1524)
				(type default)
			)
			(layer "B.SilkS")
		)
		(fp_poly
			(pts
				(xy 0.5334 0.254) (xy 0.635 0.254) (xy 0.635 0.2286) (xy 0.635 -0.254) (xy 0.5334 -0.254) (xy 0.5334 -0.2794)
				(xy -0.5334 -0.2794) (xy -0.5334 -0.254) (xy -0.635 -0.254) (xy -0.635 0.254) (xy -0.5334 0.254)
				(xy -0.5334 0.2794) (xy 0.508 0.2794) (xy 0.5334 0.2794)
			)
			(stroke
				(width 0)
				(type default)
			)
			(fill no)
			(layer "B.CrtYd")
		)
		(pad "1" smd rect
			(at -0.40005 0 180)
			(size 0.4572 0.508)
			(layers "B.Cu" "B.Mask" "B.Paste")
			(net "P1V05_NODE1")
		)
		(pad "2" smd rect
			(at 0.40005 0 180)
			(size 0.4572 0.508)
			(layers "B.Cu" "B.Mask" "B.Paste")
			(net "GND")
		)
	)
	(footprint ""
		(layer "B.Cu")
		(at 151.62276 -187.872624 -90)
		(property "Reference" "C657"
			(at -4.565396 3.38201 270)
			(unlocked yes)
			(layer "B.SilkS")
			(effects
				(font
					(size 0.7874 0.5842)
					(thickness 0.1524)
				)
				(justify left mirror)
			)
		)
		(property "Value" ""
			(at 0 0 90)
			(layer "B.Fab")
			(effects
				(font
					(size 1.27 1.27)
				)
				(justify mirror)
			)
		)
		(duplicate_pad_numbers_are_jumpers no)
		(fp_line
			(start -0.7874 0.4064)
			(end 0.7874 0.4064)
			(stroke
				(width 0.1524)
				(type default)
			)
			(layer "B.SilkS")
		)
		(fp_line
			(start 0.7874 0.4064)
			(end 0.7874 -0.4064)
			(stroke
				(width 0.1524)
				(type default)
			)
			(layer "B.SilkS")
		)
		(fp_line
			(start 0 0.381)
			(end 0 -0.381)
			(stroke
				(width 0.1524)
				(type default)
			)
			(layer "B.SilkS")
		)
		(fp_line
			(start -0.7874 -0.4064)
			(end -0.7874 0.4064)
			(stroke
				(width 0.1524)
				(type default)
			)
			(layer "B.SilkS")
		)
		(fp_line
			(start 0.7874 -0.4064)
			(end -0.7874 -0.4064)
			(stroke
				(width 0.1524)
				(type default)
			)
			(layer "B.SilkS")
		)
		(fp_poly
			(pts
				(xy 0.5334 0.254) (xy 0.635 0.254) (xy 0.635 0.2286) (xy 0.635 -0.254) (xy 0.5334 -0.254) (xy 0.5334 -0.2794)
				(xy -0.5334 -0.2794) (xy -0.5334 -0.254) (xy -0.635 -0.254) (xy -0.635 0.254) (xy -0.5334 0.254)
				(xy -0.5334 0.2794) (xy 0.508 0.2794) (xy 0.5334 0.2794)
			)
			(stroke
				(width 0)
				(type default)
			)
			(fill no)
			(layer "B.CrtYd")
		)
		(pad "1" smd rect
			(at -0.40005 0 90)
			(size 0.4572 0.508)
			(layers "B.Cu" "B.Mask" "B.Paste")
			(net "T11_NODE4_EN_R")
		)
		(pad "2" smd rect
			(at 0.40005 0 90)
			(size 0.4572 0.508)
			(layers "B.Cu" "B.Mask" "B.Paste")
			(net "GND")
		)
	)
	(footprint ""
		(layer "B.Cu")
		(at 146.79676 -184.951624 -90)
		(property "Reference" "C726"
			(at -4.357624 1.69799 270)
			(unlocked yes)
			(layer "B.SilkS")
			(effects
				(font
					(size 0.7874 0.5842)
					(thickness 0.1524)
				)
				(justify left mirror)
			)
		)
		(property "Value" ""
			(at 0 0 90)
			(layer "B.Fab")
			(effects
				(font
					(size 1.27 1.27)
				)
				(justify mirror)
			)
		)
		(duplicate_pad_numbers_are_jumpers no)
		(fp_line
			(start -0.7874 0.4064)
			(end 0.7874 0.4064)
			(stroke
				(width 0.1524)
				(type default)
			)
			(layer "B.SilkS")
		)
		(fp_line
			(start 0.7874 0.4064)
			(end 0.7874 -0.4064)
			(stroke
				(width 0.1524)
				(type default)
			)
			(layer "B.SilkS")
		)
		(fp_line
			(start 0 0.381)
			(end 0 -0.381)
			(stroke
				(width 0.1524)
				(type default)
			)
			(layer "B.SilkS")
		)
		(fp_line
			(start -0.7874 -0.4064)
			(end -0.7874 0.4064)
			(stroke
				(width 0.1524)
				(type default)
			)
			(layer "B.SilkS")
		)
		(fp_line
			(start 0.7874 -0.4064)
			(end -0.7874 -0.4064)
			(stroke
				(width 0.1524)
				(type default)
			)
			(layer "B.SilkS")
		)
		(fp_poly
			(pts
				(xy 0.5334 0.254) (xy 0.635 0.254) (xy 0.635 0.2286) (xy 0.635 -0.254) (xy 0.5334 -0.254) (xy 0.5334 -0.2794)
				(xy -0.5334 -0.2794) (xy -0.5334 -0.254) (xy -0.635 -0.254) (xy -0.635 0.254) (xy -0.5334 0.254)
				(xy -0.5334 0.2794) (xy 0.508 0.2794) (xy 0.5334 0.2794)
			)
			(stroke
				(width 0)
				(type default)
			)
			(fill no)
			(layer "B.CrtYd")
		)
		(pad "1" smd rect
			(at -0.40005 0 90)
			(size 0.4572 0.508)
			(layers "B.Cu" "B.Mask" "B.Paste")
			(net "UART_T11_NODE2_RXD")
		)
		(pad "2" smd rect
			(at 0.40005 0 90)
			(size 0.4572 0.508)
			(layers "B.Cu" "B.Mask" "B.Paste")
			(net "GND")
		)
	)
	(footprint ""
		(layer "B.Cu")
		(at 115.42776 -185.205624 -90)
		(property "Reference" "C718"
			(at -3.957828 -0.461518 270)
			(unlocked yes)
			(layer "B.SilkS")
			(effects
				(font
					(size 0.7874 0.5842)
					(thickness 0.1524)
				)
				(justify left mirror)
			)
		)
		(property "Value" ""
			(at 0 0 90)
			(layer "B.Fab")
			(effects
				(font
					(size 1.27 1.27)
				)
				(justify mirror)
			)
		)
		(duplicate_pad_numbers_are_jumpers no)
		(fp_line
			(start -0.7874 0.4064)
			(end 0.7874 0.4064)
			(stroke
				(width 0.1524)
				(type default)
			)
			(layer "B.SilkS")
		)
		(fp_line
			(start 0.7874 0.4064)
			(end 0.7874 -0.4064)
			(stroke
				(width 0.1524)
				(type default)
			)
			(layer "B.SilkS")
		)
		(fp_line
			(start 0 0.381)
			(end 0 -0.381)
			(stroke
				(width 0.1524)
				(type default)
			)
			(layer "B.SilkS")
		)
		(fp_line
			(start -0.7874 -0.4064)
			(end -0.7874 0.4064)
			(stroke
				(width 0.1524)
				(type default)
			)
			(layer "B.SilkS")
		)
		(fp_line
			(start 0.7874 -0.4064)
			(end -0.7874 -0.4064)
			(stroke
				(width 0.1524)
				(type default)
			)
			(layer "B.SilkS")
		)
		(fp_poly
			(pts
				(xy 0.5334 0.254) (xy 0.635 0.254) (xy 0.635 0.2286) (xy 0.635 -0.254) (xy 0.5334 -0.254) (xy 0.5334 -0.2794)
				(xy -0.5334 -0.2794) (xy -0.5334 -0.254) (xy -0.635 -0.254) (xy -0.635 0.254) (xy -0.5334 0.254)
				(xy -0.5334 0.2794) (xy 0.508 0.2794) (xy 0.5334 0.2794)
			)
			(stroke
				(width 0)
				(type default)
			)
			(fill no)
			(layer "B.CrtYd")
		)
		(pad "1" smd rect
			(at -0.40005 0 90)
			(size 0.4572 0.508)
			(layers "B.Cu" "B.Mask" "B.Paste")
			(net "UART_T7_NODE1_RXD")
		)
		(pad "2" smd rect
			(at 0.40005 0 90)
			(size 0.4572 0.508)
			(layers "B.Cu" "B.Mask" "B.Paste")
			(net "GND")
		)
	)
	(footprint ""
		(layer "B.Cu")
		(at 62.137036 -67.215258 90)
		(property "Reference" "R1040"
			(at -35.93592 -14.487906 270)
			(unlocked yes)
			(layer "B.SilkS")
			(effects
				(font
					(size 0.7874 0.5842)
					(thickness 0.1524)
				)
				(justify left mirror)
			)
		)
		(property "Value" ""
			(at 0 0 90)
			(layer "B.Fab")
			(effects
				(font
					(size 1.27 1.27)
				)
				(justify mirror)
			)
		)
		(duplicate_pad_numbers_are_jumpers no)
		(fp_line
			(start 0.7874 -0.4064)
			(end -0.7874 -0.4064)
			(stroke
				(width 0.1524)
				(type default)
			)
			(layer "B.SilkS")
		)
		(fp_line
			(start -0.7874 -0.4064)
			(end -0.7874 0.4064)
			(stroke
				(width 0.1524)
				(type default)
			)
			(layer "B.SilkS")
		)
		(fp_line
			(start 0.7874 0.4064)
			(end 0.7874 -0.4064)
			(stroke
				(width 0.1524)
				(type default)
			)
			(layer "B.SilkS")
		)
		(fp_line
			(start -0.7874 0.4064)
			(end 0.7874 0.4064)
			(stroke
				(width 0.1524)
				(type default)
			)
			(layer "B.SilkS")
		)
		(fp_poly
			(pts
				(xy 0.508 0.2794) (xy 0.508 0.2286) (xy 0.635 0.2286) (xy 0.635 -0.254) (xy 0.5334 -0.254) (xy 0.5334 -0.2794)
				(xy -0.5334 -0.2794) (xy -0.5334 -0.254) (xy -0.635 -0.254) (xy -0.635 0.254) (xy -0.5334 0.254)
				(xy -0.5334 0.2794)
			)
			(stroke
				(width 0)
				(type default)
			)
			(fill no)
			(layer "B.CrtYd")
		)
		(pad "1" smd rect
			(at -0.40005 0 270)
			(size 0.4572 0.508)
			(layers "B.Cu" "B.Mask" "B.Paste")
			(net "PWRGD_NODE1_DDR3_DRAM_POK")
		)
		(pad "2" smd rect
			(at 0.40005 0 270)
			(size 0.4572 0.508)
			(layers "B.Cu" "B.Mask" "B.Paste")
			(net "PV_VDDR_NODE1")
		)
	)
	(footprint ""
		(layer "B.Cu")
		(at 104.408224 -66.164206 180)
		(property "Reference" "R219"
			(at 4.686046 -0.798322 0)
			(unlocked yes)
			(layer "B.SilkS")
			(effects
				(font
					(size 0.7874 0.5842)
					(thickness 0.1524)
				)
				(justify left mirror)
			)
		)
		(property "Value" ""
			(at 0 0 0)
			(layer "B.Fab")
			(effects
				(font
					(size 1.27 1.27)
				)
				(justify mirror)
			)
		)
		(duplicate_pad_numbers_are_jumpers no)
		(fp_line
			(start 0.7874 0.4064)
			(end 0.7874 -0.4064)
			(stroke
				(width 0.1524)
				(type default)
			)
			(layer "B.SilkS")
		)
		(fp_line
			(start 0.7874 -0.4064)
			(end -0.7874 -0.4064)
			(stroke
				(width 0.1524)
				(type default)
			)
			(layer "B.SilkS")
		)
		(fp_line
			(start -0.7874 0.4064)
			(end 0.7874 0.4064)
			(stroke
				(width 0.1524)
				(type default)
			)
			(layer "B.SilkS")
		)
		(fp_line
			(start -0.7874 -0.4064)
			(end -0.7874 0.4064)
			(stroke
				(width 0.1524)
				(type default)
			)
			(layer "B.SilkS")
		)
		(fp_poly
			(pts
				(xy 0.508 0.2794) (xy 0.508 0.2286) (xy 0.635 0.2286) (xy 0.635 -0.254) (xy 0.5334 -0.254) (xy 0.5334 -0.2794)
				(xy -0.5334 -0.2794) (xy -0.5334 -0.254) (xy -0.635 -0.254) (xy -0.635 0.254) (xy -0.5334 0.254)
				(xy -0.5334 0.2794)
			)
			(stroke
				(width 0)
				(type default)
			)
			(fill no)
			(layer "B.CrtYd")
		)
		(pad "1" smd rect
			(at -0.40005 0)
			(size 0.4572 0.508)
			(layers "B.Cu" "B.Mask" "B.Paste")
			(net "XDP_CPU_NODE1_PWROK_R")
		)
		(pad "2" smd rect
			(at 0.40005 0)
			(size 0.4572 0.508)
			(layers "B.Cu" "B.Mask" "B.Paste")
			(net "XDP_CPU_NODE1_PWROK")
		)
	)
)
